# TIMECARD (Time Appliance Project (Time Card)) — schematic netlist excerpt (pin names and nets, part order shuffled) for the footprints in the layout excerpt that follows; sources: Cadence DE-HDL packaged netlist, KiCad conversion of R4006-B0001-02_R01.brd

C88  CAPACITOR  0.1UF 25V 10%  pkg SMC_0402R_H022  page 24 : \1\ = XP3R3V_FT4232 ; \2\ = SG
C125  CAPACITOR  47UF 4V 20%  pkg SMC_0805R_H057  page 14 : \1\ = FPGA_MGTAVTT ; \2\ = SG

(kicad_pcb
	(version 20260206)
	(generator "pcbnew")
	(generator_version "10.0")
	(general
		(thickness 1.6)
		(legacy_teardrops no)
	)
	(paper "A4")
	(title_block
		(title "timecard-production-celestica-r4006 — R4006-B0001-02_R01.brd")
		(comment 1 "Time Appliance Project (Time Card) / footprints 1037-1038 of 1113")
	)
	(layers
		(0 "F.Cu" signal "TOP")
		(4 "In1.Cu" signal "L02_GND1")
		(6 "In2.Cu" signal "L03_SIG1")
		(8 "In3.Cu" signal "L04_GND2")
		(10 "In4.Cu" signal "L05_VCC1")
		(12 "In5.Cu" signal "L06_VCC2")
		(14 "In6.Cu" signal "L07_GND3")
		(16 "In7.Cu" signal "L08_SIG2")
		(18 "In8.Cu" signal "L09_GND4")
		(2 "B.Cu" signal "BOTTOM")
		(9 "F.Adhes" user "F.Adhesive")
		(11 "B.Adhes" user "B.Adhesive")
		(13 "F.Paste" user "Package Geometry/Pastemask Top")
		(15 "B.Paste" user "Package Geometry/Pastemask Bottom")
		(5 "F.SilkS" user "Ref Des/Silkscreen Top")
		(7 "B.SilkS" user "Ref Des/Silkscreen Bottom")
		(1 "F.Mask" user "Board Geometry/Soldermask Top")
		(3 "B.Mask" user "Board Geometry/Soldermask Bottom")
		(17 "Dwgs.User" user "User.Drawings")
		(19 "Cmts.User" user "User.Comments")
		(21 "Eco1.User" user "User.Eco1")
		(23 "Eco2.User" user "User.Eco2")
		(25 "Edge.Cuts" user "Board Geometry/Outline")
		(27 "Margin" user)
		(31 "F.CrtYd" user "Package Geometry/Place Bound Top")
		(29 "B.CrtYd" user "Package Geometry/Place Bound Bottom")
		(35 "F.Fab" user "Ref Des/Assembly Top")
		(33 "B.Fab" user "Ref Des/Assembly Bottom")
	)
	(footprint ""
		(layer "B.Cu")
		(at 96.139 -33.909 90)
		(property "Reference" "C125"
			(at -2.19837 -0.889 0)
			(unlocked yes)
			(layer "B.SilkS")
			(effects
				(font
					(size 0.7874 0.5842)
					(thickness 0.1524)
				)
				(justify mirror)
			)
		)
		(property "Value" "VAL*"
			(at -0.0762 3.134106 90)
			(unlocked yes)
			(layer "B.Fab")
			(hide yes)
			(effects
				(font
					(size 0.7874 0.5842)
					(thickness 0.1524)
				)
				(justify mirror)
			)
		)
		(property "Tolerance" "TOL*"
			(at -0.0762 4.048506 90)
			(unlocked yes)
			(layer "Cmts.User")
			(hide yes)
			(effects
				(font
					(size 0.7874 0.5842)
					(thickness 0.1524)
				)
				(justify mirror)
			)
		)
		(property "User Part Number" "PARTNUM*"
			(at -0.1016 5.013706 90)
			(unlocked yes)
			(layer "Cmts.User")
			(hide yes)
			(effects
				(font
					(size 0.7874 0.5842)
					(thickness 0.1524)
				)
				(justify mirror)
			)
		)
		(property "Device Type" "CAPACITOR-G107-0F476-AM,47UF,2A"
			(at -0.0508 2.194306 90)
			(unlocked yes)
			(layer "B.Fab")
			(hide yes)
			(effects
				(font
					(size 0.7874 0.5842)
					(thickness 0.1524)
				)
				(justify mirror)
			)
		)
		(duplicate_pad_numbers_are_jumpers no)
		(fp_line
			(start 1.5748 -0.9398)
			(end 1.5748 0.9398)
			(stroke
				(width 0.1)
				(type default)
			)
			(layer "B.SilkS")
		)
		(fp_line
			(start -1.5748 -0.9398)
			(end 1.5748 -0.9398)
			(stroke
				(width 0.1)
				(type default)
			)
			(layer "B.SilkS")
		)
		(fp_line
			(start 1.5748 0.9398)
			(end -1.5748 0.9398)
			(stroke
				(width 0.1)
				(type default)
			)
			(layer "B.SilkS")
		)
		(fp_line
			(start -1.5748 0.9398)
			(end -1.5748 -0.9398)
			(stroke
				(width 0.1)
				(type default)
			)
			(layer "B.SilkS")
		)
		(fp_rect
			(start -1.5748 -0.9398)
			(end 1.5748 0.9398)
			(stroke
				(width 0)
				(type default)
			)
			(fill no)
			(layer "B.CrtYd")
		)
		(fp_line
			(start 1.016 -0.635)
			(end 1.016 0.635)
			(stroke
				(width 0.1)
				(type default)
			)
			(layer "B.Fab")
		)
		(fp_line
			(start -1.016 -0.635)
			(end 1.016 -0.635)
			(stroke
				(width 0.1)
				(type default)
			)
			(layer "B.Fab")
		)
		(fp_line
			(start 1.016 0.635)
			(end -1.016 0.635)
			(stroke
				(width 0.1)
				(type default)
			)
			(layer "B.Fab")
		)
		(fp_line
			(start -1.016 0.635)
			(end -1.016 -0.635)
			(stroke
				(width 0.1)
				(type default)
			)
			(layer "B.Fab")
		)
		(pad "1" smd rect
			(at 0.8382 0 270)
			(size 0.9652 1.3716)
			(layers "B.Cu" "B.Mask" "B.Paste")
			(net "FPGA_MGTAVTT")
		)
		(pad "2" smd rect
			(at -0.8382 0 270)
			(size 0.9652 1.3716)
			(layers "B.Cu" "B.Mask" "B.Paste")
			(net "SG")
		)
		(zone
			(layer "B.Cu")
			(hatch none 0.5)
			(connect_pads
				(clearance 0)
			)
			(min_thickness 0.25)
			(keepout
				(tracks allowed)
				(vias not_allowed)
				(pads allowed)
				(copperpour not_allowed)
				(footprints allowed)
			)
			(placement
				(enabled no)
				(sheetname "")
			)
			(fill
				(thermal_gap 0.5)
				(thermal_bridge_width 0.5)
				(island_removal_mode 0)
			)
			(polygon
				(pts
					(xy 95.504 -33.6804) (xy 96.774 -33.6804) (xy 96.774 -34.1376) (xy 95.504 -34.1376)
				)
			)
		)
	)
	(footprint ""
		(layer "B.Cu")
		(at 41.402 -89.535 90)
		(property "Reference" "C88"
			(at -2.413 -0.03937 270)
			(unlocked yes)
			(layer "B.SilkS")
			(effects
				(font
					(size 0.7874 0.5842)
					(thickness 0.1524)
				)
				(justify mirror)
			)
		)
		(property "Value" "VAL*"
			(at -0.0762 2.067306 90)
			(unlocked yes)
			(layer "B.Fab")
			(hide yes)
			(effects
				(font
					(size 0.7874 0.5842)
					(thickness 0.1524)
				)
				(justify mirror)
			)
		)
		(property "Device Type" "CAPACITOR-G105-0B104-EK,0.1UF,A"
			(at -0.0508 1.127506 90)
			(unlocked yes)
			(layer "B.Fab")
			(hide yes)
			(effects
				(font
					(size 0.7874 0.5842)
					(thickness 0.1524)
				)
				(justify mirror)
			)
		)
		(property "User Part Number" "PARTNUM*"
			(at -0.1016 4.023106 90)
			(unlocked yes)
			(layer "Cmts.User")
			(hide yes)
			(effects
				(font
					(size 0.7874 0.5842)
					(thickness 0.1524)
				)
				(justify mirror)
			)
		)
		(property "Tolerance" "TOL*"
			(at -0.0762 3.032506 90)
			(unlocked yes)
			(layer "Cmts.User")
			(hide yes)
			(effects
				(font
					(size 0.7874 0.5842)
					(thickness 0.1524)
				)
				(justify mirror)
			)
		)
		(duplicate_pad_numbers_are_jumpers no)
		(fp_line
			(start 1.143 -0.5588)
			(end 1.143 0.5588)
			(stroke
				(width 0.1)
				(type default)
			)
			(layer "B.SilkS")
		)
		(fp_line
			(start -1.143 -0.5588)
			(end 1.143 -0.5588)
			(stroke
				(width 0.1)
				(type default)
			)
			(layer "B.SilkS")
		)
		(fp_line
			(start 1.143 0.5588)
			(end -1.143 0.5588)
			(stroke
				(width 0.1)
				(type default)
			)
			(layer "B.SilkS")
		)
		(fp_line
			(start -1.143 0.5588)
			(end -1.143 -0.5588)
			(stroke
				(width 0.1)
				(type default)
			)
			(layer "B.SilkS")
		)
		(fp_rect
			(start 1.143 -0.5588)
			(end -1.143 0.5588)
			(stroke
				(width 0)
				(type default)
			)
			(fill no)
			(layer "B.CrtYd")
		)
		(fp_line
			(start 0.508 -0.3048)
			(end 0.508 0.3048)
			(stroke
				(width 0.1)
				(type default)
			)
			(layer "B.Fab")
		)
		(fp_line
			(start -0.508 -0.3048)
			(end 0.508 -0.3048)
			(stroke
				(width 0.1)
				(type default)
			)
			(layer "B.Fab")
		)
		(fp_line
			(start 0.508 0.3048)
			(end -0.508 0.3048)
			(stroke
				(width 0.1)
				(type default)
			)
			(layer "B.Fab")
		)
		(fp_line
			(start -0.508 0.3048)
			(end -0.508 -0.3048)
			(stroke
				(width 0.1)
				(type default)
			)
			(layer "B.Fab")
		)
		(pad "1" smd rect
			(at 0.5334 0 270)
			(size 0.7112 0.6096)
			(layers "B.Cu" "B.Mask" "B.Paste")
			(net "XP3R3V_FT4232")
		)
		(pad "2" smd rect
			(at -0.5334 0 270)
			(size 0.7112 0.6096)
			(layers "B.Cu" "B.Mask" "B.Paste")
			(net "SG")
		)
		(zone
			(layer "B.Cu")
			(hatch none 0.5)
			(connect_pads
				(clearance 0)
			)
			(min_thickness 0.25)
			(keepout
				(tracks allowed)
				(vias not_allowed)
				(pads allowed)
				(copperpour not_allowed)
				(footprints allowed)
			)
			(placement
				(enabled no)
				(sheetname "")
			)
			(fill
				(thermal_gap 0.5)
				(thermal_bridge_width 0.5)
				(island_removal_mode 0)
			)
			(polygon
				(pts
					(xy 41.0972 -89.6112) (xy 41.0972 -89.4588) (xy 41.7068 -89.4588) (xy 41.7068 -89.6112)
				)
			)
		)
	)
)
